(kicad_pcb
	(version 20260206)
	(generator "pcbnew")
	(generator_version "10.0")
	(general
		(thickness 1.6)
		(legacy_teardrops no)
	)
	(paper "A4")
	(title_block
		(title "timecard-production-celestica-r4006 — R4006-B0001-02_R01.brd")
		(comment 1 "Time Appliance Project (Time Card) / footprints 842-846 of 1113")
	)
	(layers
		(0 "F.Cu" signal "TOP")
		(4 "In1.Cu" signal "L02_GND1")
		(6 "In2.Cu" signal "L03_SIG1")
		(8 "In3.Cu" signal "L04_GND2")
		(10 "In4.Cu" signal "L05_VCC1")
		(12 "In5.Cu" signal "L06_VCC2")
		(14 "In6.Cu" signal "L07_GND3")
		(16 "In7.Cu" signal "L08_SIG2")
		(18 "In8.Cu" signal "L09_GND4")
		(2 "B.Cu" signal "BOTTOM")
		(9 "F.Adhes" user "F.Adhesive")
		(11 "B.Adhes" user "B.Adhesive")
		(13 "F.Paste" user "Package Geometry/Pastemask Top")
		(15 "B.Paste" user "Package Geometry/Pastemask Bottom")
		(5 "F.SilkS" user "Ref Des/Silkscreen Top")
		(7 "B.SilkS" user "Ref Des/Silkscreen Bottom")
		(1 "F.Mask" user "Board Geometry/Soldermask Top")
		(3 "B.Mask" user "Board Geometry/Soldermask Bottom")
		(17 "Dwgs.User" user "User.Drawings")
		(19 "Cmts.User" user "User.Comments")
		(21 "Eco1.User" user "User.Eco1")
		(23 "Eco2.User" user "User.Eco2")
		(25 "Edge.Cuts" user "Board Geometry/Outline")
		(27 "Margin" user)
		(31 "F.CrtYd" user "Package Geometry/Place Bound Top")
		(29 "B.CrtYd" user "Package Geometry/Place Bound Bottom")
		(35 "F.Fab" user "Ref Des/Assembly Top")
		(33 "B.Fab" user "Ref Des/Assembly Bottom")
	)
	(footprint ""
		(layer "B.Cu")
		(at 115.062 -29.464 90)
		(property "Reference" "R440"
			(at -3.556 0.08763 270)
			(unlocked yes)
			(layer "B.SilkS")
			(effects
				(font
					(size 0.7874 0.5842)
					(thickness 0.1524)
				)
				(justify mirror)
			)
		)
		(property "Value" "VAL*"
			(at -0.02032 2.13233 90)
			(unlocked yes)
			(layer "B.Fab")
			(hide yes)
			(effects
				(font
					(size 0.7874 0.5842)
					(thickness 0.1524)
				)
				(justify mirror)
			)
		)
		(property "Tolerance" "TOL*"
			(at -0.044704 3.05435 90)
			(unlocked yes)
			(layer "Cmts.User")
			(hide yes)
			(effects
				(font
					(size 0.7874 0.5842)
					(thickness 0.1524)
				)
				(justify mirror)
			)
		)
		(property "User Part Number" "PARTNUM*"
			(at -0.02032 4.024884 90)
			(unlocked yes)
			(layer "Cmts.User")
			(hide yes)
			(effects
				(font
					(size 0.7874 0.5842)
					(thickness 0.1524)
				)
				(justify mirror)
			)
		)
		(property "Device Type" "RESISTOR-G155-11002-01,10KOHM,A"
			(at -0.008382 1.210564 90)
			(unlocked yes)
			(layer "B.Fab")
			(hide yes)
			(effects
				(font
					(size 0.7874 0.5842)
					(thickness 0.1524)
				)
				(justify mirror)
			)
		)
		(duplicate_pad_numbers_are_jumpers no)
		(fp_line
			(start 1.143 -0.5588)
			(end 1.143 0.5588)
			(stroke
				(width 0.1)
				(type default)
			)
			(layer "B.SilkS")
		)
		(fp_line
			(start -1.143 -0.5588)
			(end 1.143 -0.5588)
			(stroke
				(width 0.1)
				(type default)
			)
			(layer "B.SilkS")
		)
		(fp_line
			(start 1.143 0.5588)
			(end -1.143 0.5588)
			(stroke
				(width 0.1)
				(type default)
			)
			(layer "B.SilkS")
		)
		(fp_line
			(start -1.143 0.5588)
			(end -1.143 -0.5588)
			(stroke
				(width 0.1)
				(type default)
			)
			(layer "B.SilkS")
		)
		(fp_poly
			(pts
				(xy 1.143 0.5588) (xy -1.143 0.5588) (xy -1.143 -0.5588) (xy 1.143 -0.5588)
			)
			(stroke
				(width 0)
				(type default)
			)
			(fill no)
			(layer "B.CrtYd")
		)
		(fp_line
			(start 0.508 -0.3048)
			(end 0.508 0.3048)
			(stroke
				(width 0.1)
				(type default)
			)
			(layer "B.Fab")
		)
		(fp_line
			(start -0.508 -0.3048)
			(end 0.508 -0.3048)
			(stroke
				(width 0.1)
				(type default)
			)
			(layer "B.Fab")
		)
		(fp_line
			(start 0.508 0.3048)
			(end -0.508 0.3048)
			(stroke
				(width 0.1)
				(type default)
			)
			(layer "B.Fab")
		)
		(fp_line
			(start -0.508 0.3048)
			(end -0.508 -0.3048)
			(stroke
				(width 0.1)
				(type default)
			)
			(layer "B.Fab")
		)
		(pad "1" smd rect
			(at 0.5334 0 270)
			(size 0.7112 0.6096)
			(layers "B.Cu" "B.Mask" "B.Paste")
			(net "FPGA_IN_MAC_PPS_OUTP")
		)
		(pad "2" smd rect
			(at -0.5334 0 270)
			(size 0.7112 0.6096)
			(layers "B.Cu" "B.Mask" "B.Paste")
			(net "SG")
		)
		(zone
			(layer "B.Cu")
			(hatch none 0.5)
			(connect_pads
				(clearance 0)
			)
			(min_thickness 0.25)
			(keepout
				(tracks not_allowed)
				(vias allowed)
				(pads allowed)
				(copperpour not_allowed)
				(footprints allowed)
			)
			(placement
				(enabled no)
				(sheetname "")
			)
			(fill
				(thermal_gap 0.5)
				(thermal_bridge_width 0.5)
				(island_removal_mode 0)
			)
			(polygon
				(pts
					(xy 115.3668 -29.5402) (xy 114.7572 -29.5402) (xy 114.7572 -29.3878) (xy 115.3668 -29.3878)
				)
			)
		)
		(zone
			(layer "B.Cu")
			(hatch none 0.5)
			(connect_pads
				(clearance 0)
			)
			(min_thickness 0.25)
			(keepout
				(tracks allowed)
				(vias not_allowed)
				(pads allowed)
				(copperpour not_allowed)
				(footprints allowed)
			)
			(placement
				(enabled no)
				(sheetname "")
			)
			(fill
				(thermal_gap 0.5)
				(thermal_bridge_width 0.5)
				(island_removal_mode 0)
			)
			(polygon
				(pts
					(xy 115.3668 -29.5402) (xy 114.7572 -29.5402) (xy 114.7572 -29.3878) (xy 115.3668 -29.3878)
				)
			)
		)
	)
	(footprint ""
		(layer "B.Cu")
		(at 109.728 -23.876 -90)
		(property "Reference" "C248"
			(at -0.127 2.96037 270)
			(unlocked yes)
			(layer "B.SilkS")
			(effects
				(font
					(size 0.7874 0.5842)
					(thickness 0.1524)
				)
				(justify mirror)
			)
		)
		(property "Value" "VAL*"
			(at -0.0762 2.067306 270)
			(unlocked yes)
			(layer "B.Fab")
			(hide yes)
			(effects
				(font
					(size 0.7874 0.5842)
					(thickness 0.1524)
				)
				(justify mirror)
			)
		)
		(property "Device Type" "CAPACITOR-G105-0B104-EK,0.1UF,A"
			(at -0.0508 1.127506 270)
			(unlocked yes)
			(layer "B.Fab")
			(hide yes)
			(effects
				(font
					(size 0.7874 0.5842)
					(thickness 0.1524)
				)
				(justify mirror)
			)
		)
		(property "User Part Number" "PARTNUM*"
			(at -0.1016 4.023106 270)
			(unlocked yes)
			(layer "Cmts.User")
			(hide yes)
			(effects
				(font
					(size 0.7874 0.5842)
					(thickness 0.1524)
				)
				(justify mirror)
			)
		)
		(property "Tolerance" "TOL*"
			(at -0.0762 3.032506 270)
			(unlocked yes)
			(layer "Cmts.User")
			(hide yes)
			(effects
				(font
					(size 0.7874 0.5842)
					(thickness 0.1524)
				)
				(justify mirror)
			)
		)
		(duplicate_pad_numbers_are_jumpers no)
		(fp_line
			(start -1.143 0.5588)
			(end -1.143 -0.5588)
			(stroke
				(width 0.1)
				(type default)
			)
			(layer "B.SilkS")
		)
		(fp_line
			(start 1.143 0.5588)
			(end -1.143 0.5588)
			(stroke
				(width 0.1)
				(type default)
			)
			(layer "B.SilkS")
		)
		(fp_line
			(start -1.143 -0.5588)
			(end 1.143 -0.5588)
			(stroke
				(width 0.1)
				(type default)
			)
			(layer "B.SilkS")
		)
		(fp_line
			(start 1.143 -0.5588)
			(end 1.143 0.5588)
			(stroke
				(width 0.1)
				(type default)
			)
			(layer "B.SilkS")
		)
		(fp_rect
			(start 1.143 -0.5588)
			(end -1.143 0.5588)
			(stroke
				(width 0)
				(type default)
			)
			(fill no)
			(layer "B.CrtYd")
		)
		(fp_line
			(start -0.508 0.3048)
			(end -0.508 -0.3048)
			(stroke
				(width 0.1)
				(type default)
			)
			(layer "B.Fab")
		)
		(fp_line
			(start 0.508 0.3048)
			(end -0.508 0.3048)
			(stroke
				(width 0.1)
				(type default)
			)
			(layer "B.Fab")
		)
		(fp_line
			(start -0.508 -0.3048)
			(end 0.508 -0.3048)
			(stroke
				(width 0.1)
				(type default)
			)
			(layer "B.Fab")
		)
		(fp_line
			(start 0.508 -0.3048)
			(end 0.508 0.3048)
			(stroke
				(width 0.1)
				(type default)
			)
			(layer "B.Fab")
		)
		(pad "1" smd rect
			(at 0.5334 0 90)
			(size 0.7112 0.6096)
			(layers "B.Cu" "B.Mask" "B.Paste")
			(net "VDD3V3_OSC_200M")
		)
		(pad "2" smd rect
			(at -0.5334 0 90)
			(size 0.7112 0.6096)
			(layers "B.Cu" "B.Mask" "B.Paste")
			(net "SG")
		)
		(zone
			(layer "B.Cu")
			(hatch none 0.5)
			(connect_pads
				(clearance 0)
			)
			(min_thickness 0.25)
			(keepout
				(tracks allowed)
				(vias not_allowed)
				(pads allowed)
				(copperpour not_allowed)
				(footprints allowed)
			)
			(placement
				(enabled no)
				(sheetname "")
			)
			(fill
				(thermal_gap 0.5)
				(thermal_bridge_width 0.5)
				(island_removal_mode 0)
			)
			(polygon
				(pts
					(xy 110.0328 -23.7998) (xy 110.0328 -23.9522) (xy 109.4232 -23.9522) (xy 109.4232 -23.7998)
				)
			)
		)
	)
	(footprint ""
		(layer "B.Cu")
		(at 89.9922 -101.2698 180)
		(property "Reference" "R36"
			(at -3.683 -0.03937 0)
			(unlocked yes)
			(layer "B.SilkS")
			(effects
				(font
					(size 0.7874 0.5842)
					(thickness 0.1524)
				)
				(justify mirror)
			)
		)
		(property "Value" "VAL*"
			(at -0.02032 2.13233 180)
			(unlocked yes)
			(layer "B.Fab")
			(hide yes)
			(effects
				(font
					(size 0.7874 0.5842)
					(thickness 0.1524)
				)
				(justify mirror)
			)
		)
		(property "Tolerance" "TOL*"
			(at -0.044704 3.05435 180)
			(unlocked yes)
			(layer "Cmts.User")
			(hide yes)
			(effects
				(font
					(size 0.7874 0.5842)
					(thickness 0.1524)
				)
				(justify mirror)
			)
		)
		(property "User Part Number" "PARTNUM*"
			(at -0.02032 4.024884 180)
			(unlocked yes)
			(layer "Cmts.User")
			(hide yes)
			(effects
				(font
					(size 0.7874 0.5842)
					(thickness 0.1524)
				)
				(justify mirror)
			)
		)
		(property "Device Type" "RESISTOR-G155-11002-01,10KOHM,A"
			(at -0.008382 1.210564 180)
			(unlocked yes)
			(layer "B.Fab")
			(hide yes)
			(effects
				(font
					(size 0.7874 0.5842)
					(thickness 0.1524)
				)
				(justify mirror)
			)
		)
		(duplicate_pad_numbers_are_jumpers no)
		(fp_line
			(start 1.143 0.5588)
			(end -1.143 0.5588)
			(stroke
				(width 0.1)
				(type default)
			)
			(layer "B.SilkS")
		)
		(fp_line
			(start 1.143 -0.5588)
			(end 1.143 0.5588)
			(stroke
				(width 0.1)
				(type default)
			)
			(layer "B.SilkS")
		)
		(fp_line
			(start -1.143 0.5588)
			(end -1.143 -0.5588)
			(stroke
				(width 0.1)
				(type default)
			)
			(layer "B.SilkS")
		)
		(fp_line
			(start -1.143 -0.5588)
			(end 1.143 -0.5588)
			(stroke
				(width 0.1)
				(type default)
			)
			(layer "B.SilkS")
		)
		(fp_rect
			(start 1.143 -0.5588)
			(end -1.143 0.5588)
			(stroke
				(width 0)
				(type default)
			)
			(fill no)
			(layer "B.CrtYd")
		)
		(fp_line
			(start 0.508 0.3048)
			(end -0.508 0.3048)
			(stroke
				(width 0.1)
				(type default)
			)
			(layer "B.Fab")
		)
		(fp_line
			(start 0.508 -0.3048)
			(end 0.508 0.3048)
			(stroke
				(width 0.1)
				(type default)
			)
			(layer "B.Fab")
		)
		(fp_line
			(start -0.508 0.3048)
			(end -0.508 -0.3048)
			(stroke
				(width 0.1)
				(type default)
			)
			(layer "B.Fab")
		)
		(fp_line
			(start -0.508 -0.3048)
			(end 0.508 -0.3048)
			(stroke
				(width 0.1)
				(type default)
			)
			(layer "B.Fab")
		)
		(pad "1" smd rect
			(at 0.5334 0)
			(size 0.7112 0.6096)
			(layers "B.Cu" "B.Mask" "B.Paste")
			(net "XP3R3V_COMP")
		)
		(pad "2" smd rect
			(at -0.5334 0)
			(size 0.7112 0.6096)
			(layers "B.Cu" "B.Mask" "B.Paste")
			(net "UNNAMED_517_CAPACITOR_I17_1")
		)
		(zone
			(layer "B.Cu")
			(hatch none 0.5)
			(connect_pads
				(clearance 0)
			)
			(min_thickness 0.25)
			(keepout
				(tracks allowed)
				(vias not_allowed)
				(pads allowed)
				(copperpour not_allowed)
				(footprints allowed)
			)
			(placement
				(enabled no)
				(sheetname "")
			)
			(fill
				(thermal_gap 0.5)
				(thermal_bridge_width 0.5)
				(island_removal_mode 0)
			)
			(polygon
				(pts
					(xy 89.916 -100.965) (xy 90.0684 -100.965) (xy 90.0684 -101.5746) (xy 89.916 -101.5746)
				)
			)
		)
	)
	(footprint ""
		(layer "B.Cu")
		(at 5.588 -75.565 180)
		(property "Reference" "R337"
			(at 3.048 0.59563 0)
			(unlocked yes)
			(layer "B.SilkS")
			(effects
				(font
					(size 0.7874 0.5842)
					(thickness 0.1524)
				)
				(justify mirror)
			)
		)
		(property "Value" "VAL*"
			(at -0.02032 2.13233 180)
			(unlocked yes)
			(layer "B.Fab")
			(hide yes)
			(effects
				(font
					(size 0.7874 0.5842)
					(thickness 0.1524)
				)
				(justify mirror)
			)
		)
		(property "Tolerance" "TOL*"
			(at -0.044704 3.05435 180)
			(unlocked yes)
			(layer "Cmts.User")
			(hide yes)
			(effects
				(font
					(size 0.7874 0.5842)
					(thickness 0.1524)
				)
				(justify mirror)
			)
		)
		(property "User Part Number" "PARTNUM*"
			(at -0.02032 4.024884 180)
			(unlocked yes)
			(layer "Cmts.User")
			(hide yes)
			(effects
				(font
					(size 0.7874 0.5842)
					(thickness 0.1524)
				)
				(justify mirror)
			)
		)
		(property "Device Type" "RESISTOR-G155-14701-01,4.7KOHMA"
			(at -0.008382 1.210564 180)
			(unlocked yes)
			(layer "B.Fab")
			(hide yes)
			(effects
				(font
					(size 0.7874 0.5842)
					(thickness 0.1524)
				)
				(justify mirror)
			)
		)
		(duplicate_pad_numbers_are_jumpers no)
		(fp_line
			(start 1.143 0.5588)
			(end -1.143 0.5588)
			(stroke
				(width 0.1)
				(type default)
			)
			(layer "B.SilkS")
		)
		(fp_line
			(start 1.143 -0.5588)
			(end 1.143 0.5588)
			(stroke
				(width 0.1)
				(type default)
			)
			(layer "B.SilkS")
		)
		(fp_line
			(start -1.143 0.5588)
			(end -1.143 -0.5588)
			(stroke
				(width 0.1)
				(type default)
			)
			(layer "B.SilkS")
		)
		(fp_line
			(start -1.143 -0.5588)
			(end 1.143 -0.5588)
			(stroke
				(width 0.1)
				(type default)
			)
			(layer "B.SilkS")
		)
		(fp_rect
			(start -1.143 0.5588)
			(end 1.143 -0.5588)
			(stroke
				(width 0)
				(type default)
			)
			(fill no)
			(layer "B.CrtYd")
		)
		(fp_line
			(start 0.508 0.3048)
			(end -0.508 0.3048)
			(stroke
				(width 0.1)
				(type default)
			)
			(layer "B.Fab")
		)
		(fp_line
			(start 0.508 -0.3048)
			(end 0.508 0.3048)
			(stroke
				(width 0.1)
				(type default)
			)
			(layer "B.Fab")
		)
		(fp_line
			(start -0.508 0.3048)
			(end -0.508 -0.3048)
			(stroke
				(width 0.1)
				(type default)
			)
			(layer "B.Fab")
		)
		(fp_line
			(start -0.508 -0.3048)
			(end 0.508 -0.3048)
			(stroke
				(width 0.1)
				(type default)
			)
			(layer "B.Fab")
		)
		(pad "1" smd rect
			(at 0.5334 0)
			(size 0.7112 0.6096)
			(layers "B.Cu" "B.Mask" "B.Paste")
			(net "XP3R3V_FPGA")
		)
		(pad "2" smd rect
			(at -0.5334 0)
			(size 0.7112 0.6096)
			(layers "B.Cu" "B.Mask" "B.Paste")
			(net "UNNAMED_6_LM75BDPTSSOP8_I34_A0")
		)
		(zone
			(layer "B.Cu")
			(hatch none 0.5)
			(connect_pads
				(clearance 0)
			)
			(min_thickness 0.25)
			(keepout
				(tracks allowed)
				(vias not_allowed)
				(pads allowed)
				(copperpour not_allowed)
				(footprints allowed)
			)
			(placement
				(enabled no)
				(sheetname "")
			)
			(fill
				(thermal_gap 0.5)
				(thermal_bridge_width 0.5)
				(island_removal_mode 0)
			)
			(polygon
				(pts
					(xy 5.6642 -75.8698) (xy 5.5118 -75.8698) (xy 5.5118 -75.2602) (xy 5.6642 -75.2602)
				)
			)
		)
	)
	(footprint ""
		(layer "B.Cu")
		(at 154.153108 -49.01311 90)
		(property "Reference" "R65"
			(at 3.56489 -0.141478 270)
			(unlocked yes)
			(layer "B.SilkS")
			(effects
				(font
					(size 0.7874 0.5842)
					(thickness 0.1524)
				)
				(justify mirror)
			)
		)
		(property "Value" "VAL*"
			(at -0.02032 2.13233 90)
			(unlocked yes)
			(layer "B.Fab")
			(hide yes)
			(effects
				(font
					(size 0.7874 0.5842)
					(thickness 0.1524)
				)
				(justify mirror)
			)
		)
		(property "Device Type" "RESISTOR-G155-14701-01,4.7KOHMA"
			(at -0.008382 1.210564 90)
			(unlocked yes)
			(layer "B.Fab")
			(hide yes)
			(effects
				(font
					(size 0.7874 0.5842)
					(thickness 0.1524)
				)
				(justify mirror)
			)
		)
		(property "User Part Number" "PARTNUM*"
			(at -0.02032 4.024884 90)
			(unlocked yes)
			(layer "Cmts.User")
			(hide yes)
			(effects
				(font
					(size 0.7874 0.5842)
					(thickness 0.1524)
				)
				(justify mirror)
			)
		)
		(property "Tolerance" "TOL*"
			(at -0.044704 3.05435 90)
			(unlocked yes)
			(layer "Cmts.User")
			(hide yes)
			(effects
				(font
					(size 0.7874 0.5842)
					(thickness 0.1524)
				)
				(justify mirror)
			)
		)
		(duplicate_pad_numbers_are_jumpers no)
		(fp_line
			(start 1.143 -0.5588)
			(end 1.143 0.5588)
			(stroke
				(width 0.1)
				(type default)
			)
			(layer "B.SilkS")
		)
		(fp_line
			(start -1.143 -0.5588)
			(end 1.143 -0.5588)
			(stroke
				(width 0.1)
				(type default)
			)
			(layer "B.SilkS")
		)
		(fp_line
			(start 1.143 0.5588)
			(end -1.143 0.5588)
			(stroke
				(width 0.1)
				(type default)
			)
			(layer "B.SilkS")
		)
		(fp_line
			(start -1.143 0.5588)
			(end -1.143 -0.5588)
			(stroke
				(width 0.1)
				(type default)
			)
			(layer "B.SilkS")
		)
		(fp_rect
			(start 1.143 0.5588)
			(end -1.143 -0.5588)
			(stroke
				(width 0)
				(type default)
			)
			(fill no)
			(layer "B.CrtYd")
		)
		(fp_line
			(start 0.508 -0.3048)
			(end 0.508 0.3048)
			(stroke
				(width 0.1)
				(type default)
			)
			(layer "B.Fab")
		)
		(fp_line
			(start -0.508 -0.3048)
			(end 0.508 -0.3048)
			(stroke
				(width 0.1)
				(type default)
			)
			(layer "B.Fab")
		)
		(fp_line
			(start 0.508 0.3048)
			(end -0.508 0.3048)
			(stroke
				(width 0.1)
				(type default)
			)
			(layer "B.Fab")
		)
		(fp_line
			(start -0.508 0.3048)
			(end -0.508 -0.3048)
			(stroke
				(width 0.1)
				(type default)
			)
			(layer "B.Fab")
		)
		(pad "1" smd rect
			(at 0.5334 0 270)
			(size 0.7112 0.6096)
			(layers "B.Cu" "B.Mask" "B.Paste")
			(net "XP3R3V_FPGA")
		)
		(pad "2" smd rect
			(at -0.5334 0 270)
			(size 0.7112 0.6096)
			(layers "B.Cu" "B.Mask" "B.Paste")
			(net "SHT3X_I2C_SCL")
		)
		(zone
			(layer "B.Cu")
			(hatch none 0.5)
			(connect_pads
				(clearance 0)
			)
			(min_thickness 0.25)
			(keepout
				(tracks allowed)
				(vias not_allowed)
				(pads allowed)
				(copperpour not_allowed)
				(footprints allowed)
			)
			(placement
				(enabled no)
				(sheetname "")
			)
			(fill
				(thermal_gap 0.5)
				(thermal_bridge_width 0.5)
				(island_removal_mode 0)
			)
			(polygon
				(pts
					(xy 154.457908 -49.08931) (xy 153.848308 -49.08931) (xy 153.848308 -48.93691) (xy 154.457908 -48.93691)
				)
			)
		)
	)
)
